(kicad_pcb
	(version 20260206)
	(generator "pcbnew")
	(generator_version "10.0")
	(general
		(thickness 1.6)
		(legacy_teardrops no)
	)
	(paper "A4")
	(title_block
		(title "panther-plus-userver — 13130-1b_20150205.brd")
		(comment 1 "Honey Badger (Wiwynn) / footprints 283-291 of 1509")
	)
	(layers
		(0 "F.Cu" signal "TOP")
		(4 "In1.Cu" signal "L2")
		(6 "In2.Cu" signal "L3")
		(8 "In3.Cu" signal "L4")
		(10 "In4.Cu" signal "L5")
		(12 "In5.Cu" signal "L6")
		(14 "In6.Cu" signal "L7")
		(16 "In7.Cu" signal "L8")
		(18 "In8.Cu" signal "L9")
		(20 "In9.Cu" signal "L10")
		(22 "In10.Cu" signal "L11")
		(2 "B.Cu" signal "BOTTOM")
		(9 "F.Adhes" user "F.Adhesive")
		(11 "B.Adhes" user "B.Adhesive")
		(13 "F.Paste" user "Package Geometry/Pastemask Top")
		(15 "B.Paste" user "Package Geometry/Pastemask Bottom")
		(5 "F.SilkS" user "Ref Des/Silkscreen Top")
		(7 "B.SilkS" user "Ref Des/Silkscreen Bottom")
		(1 "F.Mask" user "Board Geometry/Soldermask Top")
		(3 "B.Mask" user "Board Geometry/Soldermask Bottom")
		(17 "Dwgs.User" user "User.Drawings")
		(19 "Cmts.User" user "User.Comments")
		(21 "Eco1.User" user "User.Eco1")
		(23 "Eco2.User" user "User.Eco2")
		(25 "Edge.Cuts" user "Board Geometry/Outline")
		(27 "Margin" user)
		(31 "F.CrtYd" user "Package Geometry/Place Bound Top")
		(29 "B.CrtYd" user "Package Geometry/Place Bound Bottom")
		(35 "F.Fab" user "Ref Des/Assembly Top")
		(33 "B.Fab" user "Ref Des/Assembly Bottom")
	)
	(footprint ""
		(layer "F.Cu")
		(at 15.24 -31.877)
		(property "Reference" "PR196"
			(at 0 0 0)
			(layer "F.SilkS")
			(hide yes)
			(effects
				(font
					(size 1.27 1.27)
				)
			)
		)
		(property "Value" "10KR2F-2-GP"
			(at 1.7907 -1.1176 0)
			(unlocked yes)
			(layer "F.Fab")
			(hide yes)
			(effects
				(font
					(size 1.016 1.016)
					(thickness 0.1524)
				)
			)
		)
		(property "Device Type" "R402H16"
			(at 1.7907 -2.6416 0)
			(unlocked yes)
			(layer "F.Fab")
			(hide yes)
			(effects
				(font
					(size 1.016 1.016)
					(thickness 0.1524)
				)
			)
		)
		(duplicate_pad_numbers_are_jumpers no)
		(fp_rect
			(start -0.381 0.8382)
			(end 0.381 -0.8382)
			(stroke
				(width 0)
				(type default)
			)
			(fill no)
			(layer "F.CrtYd")
		)
		(fp_rect
			(start -0.381 0.8382)
			(end 0.381 -0.8382)
			(stroke
				(width 0)
				(type default)
			)
			(fill no)
			(layer "F.Fab")
		)
		(pad "1" smd custom
			(at 0 -0.4318)
			(size 0.127 0.127)
			(layers "F.Cu" "F.Mask" "F.Paste")
			(net "P3V3_STBY_EN")
			(options
				(clearance outline)
				(anchor circle)
			)
			(primitives
				(gr_poly
					(pts
						(arc
							(start -0.2032 -0.2794)
							(mid -0.239121 -0.264521)
							(end -0.254 -0.2286)
						)
						(arc
							(start -0.254 0.2286)
							(mid -0.239121 0.264521)
							(end -0.2032 0.2794)
						)
						(arc
							(start 0.2032 0.2794)
							(mid 0.239121 0.264521)
							(end 0.254 0.2286)
						)
						(arc
							(start 0.254 -0.2286)
							(mid 0.239121 -0.264521)
							(end 0.2032 -0.2794)
						)
					)
					(width 0)
					(fill yes)
				)
			)
		)
		(pad "2" smd custom
			(at 0 0.4318)
			(size 0.127 0.127)
			(layers "F.Cu" "F.Mask" "F.Paste")
			(net "P12V")
			(options
				(clearance outline)
				(anchor circle)
			)
			(primitives
				(gr_poly
					(pts
						(arc
							(start -0.2032 -0.2794)
							(mid -0.239121 -0.264521)
							(end -0.254 -0.2286)
						)
						(arc
							(start -0.254 0.2286)
							(mid -0.239121 0.264521)
							(end -0.2032 0.2794)
						)
						(arc
							(start 0.2032 0.2794)
							(mid 0.239121 0.264521)
							(end 0.254 0.2286)
						)
						(arc
							(start 0.254 -0.2286)
							(mid 0.239121 -0.264521)
							(end 0.2032 -0.2794)
						)
					)
					(width 0)
					(fill yes)
				)
			)
		)
	)
	(footprint ""
		(layer "F.Cu")
		(at 154.7876 -59.309)
		(property "Reference" "C329"
			(at 0 0 0)
			(layer "F.SilkS")
			(hide yes)
			(effects
				(font
					(size 1.27 1.27)
				)
			)
		)
		(property "Value" "SCD1U16V2KX-3GP"
			(at 1.8923 -1.2065 0)
			(unlocked yes)
			(layer "F.Fab")
			(hide yes)
			(effects
				(font
					(size 1.016 1.016)
					(thickness 0.1524)
				)
			)
		)
		(property "Device Type" "C402H22"
			(at 1.8923 -2.7305 0)
			(unlocked yes)
			(layer "F.Fab")
			(hide yes)
			(effects
				(font
					(size 1.016 1.016)
					(thickness 0.1524)
				)
			)
		)
		(duplicate_pad_numbers_are_jumpers no)
		(fp_rect
			(start -0.381 0.7366)
			(end 0.381 -0.7366)
			(stroke
				(width 0)
				(type default)
			)
			(fill no)
			(layer "F.CrtYd")
		)
		(fp_rect
			(start -0.381 0.7366)
			(end 0.381 -0.7366)
			(stroke
				(width 0)
				(type default)
			)
			(fill no)
			(layer "F.Fab")
		)
		(pad "1" smd custom
			(at 0 -0.4572)
			(size 0.1143 0.1143)
			(layers "F.Cu" "F.Mask" "F.Paste")
			(net "PV_VDDR")
			(options
				(clearance outline)
				(anchor circle)
			)
			(primitives
				(gr_poly
					(pts
						(arc
							(start -0.254 -0.1778)
							(mid -0.239121 -0.213721)
							(end -0.2032 -0.2286)
						)
						(arc
							(start 0.2032 -0.2286)
							(mid 0.239121 -0.213721)
							(end 0.254 -0.1778)
						)
						(arc
							(start 0.254 0.1778)
							(mid 0.239121 0.213721)
							(end 0.2032 0.2286)
						)
						(arc
							(start -0.2032 0.2286)
							(mid -0.239121 0.213721)
							(end -0.254 0.1778)
						)
					)
					(width 0)
					(fill yes)
				)
			)
		)
		(pad "2" smd custom
			(at 0 0.4572)
			(size 0.1143 0.1143)
			(layers "F.Cu" "F.Mask" "F.Paste")
			(net "GND")
			(options
				(clearance outline)
				(anchor circle)
			)
			(primitives
				(gr_poly
					(pts
						(arc
							(start -0.254 -0.1778)
							(mid -0.239121 -0.213721)
							(end -0.2032 -0.2286)
						)
						(arc
							(start 0.2032 -0.2286)
							(mid 0.239121 -0.213721)
							(end 0.254 -0.1778)
						)
						(arc
							(start 0.254 0.1778)
							(mid 0.239121 0.213721)
							(end 0.2032 0.2286)
						)
						(arc
							(start -0.2032 0.2286)
							(mid -0.239121 0.213721)
							(end -0.254 0.1778)
						)
					)
					(width 0)
					(fill yes)
				)
			)
		)
	)
	(footprint ""
		(layer "F.Cu")
		(at 95.758 -14.097 180)
		(property "Reference" "C319"
			(at 0 0 180)
			(layer "F.SilkS")
			(hide yes)
			(effects
				(font
					(size 1.27 1.27)
				)
			)
		)
		(property "Value" "SC22U25V5MX-GP"
			(at 0 -4.9022 180)
			(unlocked yes)
			(layer "F.Fab")
			(hide yes)
			(effects
				(font
					(size 1.016 1.016)
					(thickness 0.1524)
				)
			)
		)
		(property "Device Type" "C805H58"
			(at 0 -6.8072 180)
			(unlocked yes)
			(layer "F.Fab")
			(hide yes)
			(effects
				(font
					(size 1.016 1.016)
					(thickness 0.1524)
				)
			)
		)
		(duplicate_pad_numbers_are_jumpers no)
		(fp_line
			(start 0.6096 0)
			(end -0.6096 0)
			(stroke
				(width 0.3048)
				(type default)
			)
			(layer "F.SilkS")
		)
		(fp_poly
			(pts
				(xy -0.9017 1.4351) (xy 0.9017 1.4351) (xy 0.9017 -1.4351) (xy -0.9017 -1.4351)
			)
			(stroke
				(width 0)
				(type default)
			)
			(fill no)
			(layer "F.CrtYd")
		)
		(fp_poly
			(pts
				(xy 0.9017 1.4351) (xy 0.9017 -1.4351) (xy -0.9017 -1.4351) (xy -0.9017 1.4351)
			)
			(stroke
				(width 0)
				(type default)
			)
			(fill no)
			(layer "F.Fab")
		)
		(pad "1" smd rect
			(at 0 -0.8382 180)
			(size 1.5494 0.9398)
			(layers "F.Cu" "F.Mask" "F.Paste")
			(net "P12V")
		)
		(pad "2" smd rect
			(at 0 0.8382 180)
			(size 1.5494 0.9398)
			(layers "F.Cu" "F.Mask" "F.Paste")
			(net "GND")
		)
	)
	(footprint ""
		(layer "F.Cu")
		(at 41.3004 -39.4208 90)
		(property "Reference" "R69"
			(at 0 0 90)
			(layer "F.SilkS")
			(hide yes)
			(effects
				(font
					(size 1.27 1.27)
				)
			)
		)
		(property "Value" "8K2R2F-1-GP"
			(at 1.7907 -1.1176 90)
			(unlocked yes)
			(layer "F.Fab")
			(hide yes)
			(effects
				(font
					(size 1.016 1.016)
					(thickness 0.1524)
				)
			)
		)
		(property "Device Type" "R402H16"
			(at 1.7907 -2.6416 90)
			(unlocked yes)
			(layer "F.Fab")
			(hide yes)
			(effects
				(font
					(size 1.016 1.016)
					(thickness 0.1524)
				)
			)
		)
		(duplicate_pad_numbers_are_jumpers no)
		(fp_rect
			(start -0.381 0.8382)
			(end 0.381 -0.8382)
			(stroke
				(width 0)
				(type default)
			)
			(fill no)
			(layer "F.CrtYd")
		)
		(fp_rect
			(start -0.381 0.8382)
			(end 0.381 -0.8382)
			(stroke
				(width 0)
				(type default)
			)
			(fill no)
			(layer "F.Fab")
		)
		(pad "1" smd custom
			(at 0 -0.4318 90)
			(size 0.127 0.127)
			(layers "F.Cu" "F.Mask" "F.Paste")
			(net "P3V3")
			(options
				(clearance outline)
				(anchor circle)
			)
			(primitives
				(gr_poly
					(pts
						(arc
							(start -0.2032 -0.2794)
							(mid -0.239121 -0.264521)
							(end -0.254 -0.2286)
						)
						(arc
							(start -0.254 0.2286)
							(mid -0.239121 0.264521)
							(end -0.2032 0.2794)
						)
						(arc
							(start 0.2032 0.2794)
							(mid 0.239121 0.264521)
							(end 0.254 0.2286)
						)
						(arc
							(start 0.254 -0.2286)
							(mid 0.239121 -0.264521)
							(end 0.2032 -0.2794)
						)
					)
					(width 0)
					(fill yes)
				)
			)
		)
		(pad "2" smd custom
			(at 0 0.4318 90)
			(size 0.127 0.127)
			(layers "F.Cu" "F.Mask" "F.Paste")
			(net "CLK_GEN_DELAY0_PG")
			(options
				(clearance outline)
				(anchor circle)
			)
			(primitives
				(gr_poly
					(pts
						(arc
							(start -0.2032 -0.2794)
							(mid -0.239121 -0.264521)
							(end -0.254 -0.2286)
						)
						(arc
							(start -0.254 0.2286)
							(mid -0.239121 0.264521)
							(end -0.2032 0.2794)
						)
						(arc
							(start 0.2032 0.2794)
							(mid 0.239121 0.264521)
							(end 0.254 0.2286)
						)
						(arc
							(start 0.254 -0.2286)
							(mid 0.239121 -0.264521)
							(end 0.2032 -0.2794)
						)
					)
					(width 0)
					(fill yes)
				)
			)
		)
	)
	(footprint ""
		(layer "F.Cu")
		(at 25.1206 -51.3588)
		(property "Reference" "PC58"
			(at 0 0 0)
			(layer "F.SilkS")
			(hide yes)
			(effects
				(font
					(size 1.27 1.27)
				)
			)
		)
		(property "Value" "SC150P50V2KX-GP"
			(at 1.8923 -1.2065 0)
			(unlocked yes)
			(layer "F.Fab")
			(hide yes)
			(effects
				(font
					(size 1.016 1.016)
					(thickness 0.1524)
				)
			)
		)
		(property "Device Type" "C402H22"
			(at 1.8923 -2.7305 0)
			(unlocked yes)
			(layer "F.Fab")
			(hide yes)
			(effects
				(font
					(size 1.016 1.016)
					(thickness 0.1524)
				)
			)
		)
		(duplicate_pad_numbers_are_jumpers no)
		(fp_rect
			(start -0.381 0.7366)
			(end 0.381 -0.7366)
			(stroke
				(width 0)
				(type default)
			)
			(fill no)
			(layer "F.CrtYd")
		)
		(fp_rect
			(start -0.381 0.7366)
			(end 0.381 -0.7366)
			(stroke
				(width 0)
				(type default)
			)
			(fill no)
			(layer "F.Fab")
		)
		(pad "1" smd custom
			(at 0 -0.4572)
			(size 0.1143 0.1143)
			(layers "F.Cu" "F.Mask" "F.Paste")
			(net "VR_PVCCP_ISUMN_RC")
			(options
				(clearance outline)
				(anchor circle)
			)
			(primitives
				(gr_poly
					(pts
						(arc
							(start -0.254 -0.1778)
							(mid -0.239121 -0.213721)
							(end -0.2032 -0.2286)
						)
						(arc
							(start 0.2032 -0.2286)
							(mid 0.239121 -0.213721)
							(end 0.254 -0.1778)
						)
						(arc
							(start 0.254 0.1778)
							(mid 0.239121 0.213721)
							(end 0.2032 0.2286)
						)
						(arc
							(start -0.2032 0.2286)
							(mid -0.239121 0.213721)
							(end -0.254 0.1778)
						)
					)
					(width 0)
					(fill yes)
				)
			)
		)
		(pad "2" smd custom
			(at 0 0.4572)
			(size 0.1143 0.1143)
			(layers "F.Cu" "F.Mask" "F.Paste")
			(net "VR_PVCCP_ISUMN")
			(options
				(clearance outline)
				(anchor circle)
			)
			(primitives
				(gr_poly
					(pts
						(arc
							(start -0.254 -0.1778)
							(mid -0.239121 -0.213721)
							(end -0.2032 -0.2286)
						)
						(arc
							(start 0.2032 -0.2286)
							(mid 0.239121 -0.213721)
							(end 0.254 -0.1778)
						)
						(arc
							(start 0.254 0.1778)
							(mid 0.239121 0.213721)
							(end 0.2032 0.2286)
						)
						(arc
							(start -0.2032 0.2286)
							(mid -0.239121 0.213721)
							(end -0.254 0.1778)
						)
					)
					(width 0)
					(fill yes)
				)
			)
		)
	)
	(footprint ""
		(layer "F.Cu")
		(at 160.5026 -46.99 -90)
		(property "Reference" "U25"
			(at 0 0 270)
			(layer "F.SilkS")
			(hide yes)
			(effects
				(font
					(size 1.27 1.27)
				)
			)
		)
		(property "Value" "2N7002DW-7F-GP"
			(at -2.5654 1.1049 270)
			(unlocked yes)
			(layer "F.Fab")
			(hide yes)
			(effects
				(font
					(size 1.016 1.016)
					(thickness 0.1524)
				)
			)
		)
		(property "Device Type" "SOT-363H44"
			(at -2.5654 -0.4191 270)
			(unlocked yes)
			(layer "F.Fab")
			(hide yes)
			(effects
				(font
					(size 1.016 1.016)
					(thickness 0.1524)
				)
			)
		)
		(duplicate_pad_numbers_are_jumpers no)
		(fp_poly
			(pts
				(xy -0.6731 1.4351) (xy -0.9779 1.7399) (xy -0.381 1.7399) (xy -0.3683 1.7399) (xy -0.381 1.7272)
			)
			(stroke
				(width 0)
				(type default)
			)
			(fill yes)
			(layer "F.SilkS")
		)
		(fp_poly
			(pts
				(xy 1.2573 0.8763) (xy 1.2573 -0.8763) (xy 0.9525 -0.8763) (xy 0.9525 -1.4351) (xy -0.9525 -1.4351)
				(xy -0.9525 -0.8763) (xy -1.2573 -0.8763) (xy -1.2573 0.8763) (xy -0.9525 0.8763) (xy -0.9525 1.4351)
				(xy 0.9525 1.4351) (xy 0.9525 0.8763)
			)
			(stroke
				(width 0)
				(type default)
			)
			(fill no)
			(layer "F.CrtYd")
		)
		(fp_poly
			(pts
				(xy 1.2573 0.8763) (xy 1.2573 -0.8763) (xy 0.9525 -0.8763) (xy 0.9525 -1.4351) (xy -0.9525 -1.4351)
				(xy -0.9525 -0.8763) (xy -1.2573 -0.8763) (xy -1.2573 0.8763) (xy -0.9525 0.8763) (xy -0.9525 1.4351)
				(xy 0.9525 1.4351) (xy 0.9525 0.8763)
			)
			(stroke
				(width 0)
				(type default)
			)
			(fill no)
			(layer "F.Fab")
		)
		(pad "1" smd rect
			(at -0.65024 0.8255 270)
			(size 0.3556 0.9652)
			(layers "F.Cu" "F.Mask" "F.Paste")
			(net "XDP_SOC_CPU_TMS_S")
		)
		(pad "2" smd rect
			(at 0 0.8255 270)
			(size 0.3556 0.9652)
			(layers "F.Cu" "F.Mask" "F.Paste")
			(net "JTAG_CHAIN_EN")
		)
		(pad "3" smd rect
			(at 0.65024 0.8255 270)
			(size 0.3556 0.9652)
			(layers "F.Cu" "F.Mask" "F.Paste")
			(net "JTAG_PLD_TCK_D")
		)
		(pad "4" smd rect
			(at 0.65024 -0.8255 270)
			(size 0.3556 0.9652)
			(layers "F.Cu" "F.Mask" "F.Paste")
			(net "XDP_SOC_CPU_TCK_S")
		)
		(pad "5" smd rect
			(at 0 -0.8255 270)
			(size 0.3556 0.9652)
			(layers "F.Cu" "F.Mask" "F.Paste")
			(net "JTAG_CHAIN_EN")
		)
		(pad "6" smd rect
			(at -0.65024 -0.8255 270)
			(size 0.3556 0.9652)
			(layers "F.Cu" "F.Mask" "F.Paste")
			(net "JTAG_PLD_TMS_D")
		)
	)
	(footprint ""
		(layer "F.Cu")
		(at 157.48 -25.781)
		(property "Reference" "TP63"
			(at 0 0 0)
			(layer "F.SilkS")
			(hide yes)
			(effects
				(font
					(size 1.27 1.27)
				)
			)
		)
		(property "Value" "TPAD28-1-GP-U"
			(at 0.0508 -1.9304 0)
			(unlocked yes)
			(layer "F.Fab")
			(hide yes)
			(effects
				(font
					(size 1.016 1.016)
					(thickness 0.1524)
				)
			)
		)
		(property "Device Type" "TPAD28-1-U"
			(at 0.0508 -3.4544 0)
			(unlocked yes)
			(layer "F.Fab")
			(hide yes)
			(effects
				(font
					(size 1.016 1.016)
					(thickness 0.1524)
				)
			)
		)
		(duplicate_pad_numbers_are_jumpers no)
		(fp_poly
			(pts
				(arc
					(start 0.3556 0)
					(mid -0.3556 0)
					(end 0.3556 0)
				)
			)
			(stroke
				(width 0)
				(type default)
			)
			(fill no)
			(layer "F.CrtYd")
		)
		(fp_poly
			(pts
				(arc
					(start 0.9525 0)
					(mid -0.9525 0)
					(end 0.9525 0)
				)
			)
			(stroke
				(width 0)
				(type default)
			)
			(fill no)
			(layer "F.Fab")
		)
		(pad "1" smd circle
			(at 0 0)
			(size 0.7112 0.7112)
			(layers "F.Cu" "F.Mask" "F.Paste")
			(net "TP_FPGA_P113")
		)
	)
	(footprint ""
		(layer "F.Cu")
		(at 32.258 -38.735 180)
		(property "Reference" "R488"
			(at 0 0 180)
			(layer "F.SilkS")
			(hide yes)
			(effects
				(font
					(size 1.27 1.27)
				)
			)
		)
		(property "Value" "51R2F-2-GP"
			(at 1.7907 -1.1176 180)
			(unlocked yes)
			(layer "F.Fab")
			(hide yes)
			(effects
				(font
					(size 1.016 1.016)
					(thickness 0.1524)
				)
			)
		)
		(property "Device Type" "R402H16"
			(at 1.7907 -2.6416 180)
			(unlocked yes)
			(layer "F.Fab")
			(hide yes)
			(effects
				(font
					(size 1.016 1.016)
					(thickness 0.1524)
				)
			)
		)
		(duplicate_pad_numbers_are_jumpers no)
		(fp_rect
			(start -0.381 0.8382)
			(end 0.381 -0.8382)
			(stroke
				(width 0)
				(type default)
			)
			(fill no)
			(layer "F.CrtYd")
		)
		(fp_rect
			(start -0.381 0.8382)
			(end 0.381 -0.8382)
			(stroke
				(width 0)
				(type default)
			)
			(fill no)
			(layer "F.Fab")
		)
		(pad "1" smd custom
			(at 0 -0.4318 180)
			(size 0.127 0.127)
			(layers "F.Cu" "F.Mask" "F.Paste")
			(net "XDP_SOC_CPU_TMS")
			(options
				(clearance outline)
				(anchor circle)
			)
			(primitives
				(gr_poly
					(pts
						(arc
							(start -0.2032 -0.2794)
							(mid -0.239121 -0.264521)
							(end -0.254 -0.2286)
						)
						(arc
							(start -0.254 0.2286)
							(mid -0.239121 0.264521)
							(end -0.2032 0.2794)
						)
						(arc
							(start 0.2032 0.2794)
							(mid 0.239121 0.264521)
							(end 0.254 0.2286)
						)
						(arc
							(start 0.254 -0.2286)
							(mid 0.239121 -0.264521)
							(end 0.2032 -0.2794)
						)
					)
					(width 0)
					(fill yes)
				)
			)
		)
		(pad "2" smd custom
			(at 0 0.4318 180)
			(size 0.127 0.127)
			(layers "F.Cu" "F.Mask" "F.Paste")
			(net "GND")
			(options
				(clearance outline)
				(anchor circle)
			)
			(primitives
				(gr_poly
					(pts
						(arc
							(start -0.2032 -0.2794)
							(mid -0.239121 -0.264521)
							(end -0.254 -0.2286)
						)
						(arc
							(start -0.254 0.2286)
							(mid -0.239121 0.264521)
							(end -0.2032 0.2794)
						)
						(arc
							(start 0.2032 0.2794)
							(mid 0.239121 0.264521)
							(end 0.254 0.2286)
						)
						(arc
							(start 0.254 -0.2286)
							(mid 0.239121 -0.264521)
							(end 0.2032 -0.2794)
						)
					)
					(width 0)
					(fill yes)
				)
			)
		)
	)
	(footprint ""
		(layer "F.Cu")
		(at 141.859 -48.26 -90)
		(property "Reference" "R78"
			(at 0 0 270)
			(layer "F.SilkS")
			(hide yes)
			(effects
				(font
					(size 1.27 1.27)
				)
			)
		)
		(property "Value" "10KR2F-2-GP"
			(at 0.064008 -3.993896 270)
			(unlocked yes)
			(layer "F.Fab")
			(hide yes)
			(effects
				(font
					(size 1.016 1.016)
					(thickness 0.1524)
				)
			)
		)
		(property "Device Type" "R402H16"
			(at 0.064008 -5.517896 270)
			(unlocked yes)
			(layer "F.Fab")
			(hide yes)
			(effects
				(font
					(size 1.016 1.016)
					(thickness 0.1524)
				)
			)
		)
		(duplicate_pad_numbers_are_jumpers no)
		(fp_rect
			(start -0.381 0.8382)
			(end 0.381 -0.8382)
			(stroke
				(width 0)
				(type default)
			)
			(fill no)
			(layer "F.CrtYd")
		)
		(fp_rect
			(start -0.381 0.8382)
			(end 0.381 -0.8382)
			(stroke
				(width 0)
				(type default)
			)
			(fill no)
			(layer "F.Fab")
		)
		(pad "1" smd custom
			(at 0 -0.4318 270)
			(size 0.127 0.127)
			(layers "F.Cu" "F.Mask" "F.Paste")
			(net "P3V3_STBY")
			(options
				(clearance outline)
				(anchor circle)
			)
			(primitives
				(gr_poly
					(pts
						(arc
							(start -0.2032 -0.2794)
							(mid -0.239121 -0.264521)
							(end -0.254 -0.2286)
						)
						(arc
							(start -0.254 0.2286)
							(mid -0.239121 0.264521)
							(end -0.2032 0.2794)
						)
						(arc
							(start 0.2032 0.2794)
							(mid 0.239121 0.264521)
							(end 0.254 0.2286)
						)
						(arc
							(start 0.254 -0.2286)
							(mid 0.239121 -0.264521)
							(end 0.2032 -0.2794)
						)
					)
					(width 0)
					(fill yes)
				)
			)
		)
		(pad "2" smd custom
			(at 0 0.4318 270)
			(size 0.127 0.127)
			(layers "F.Cu" "F.Mask" "F.Paste")
			(net "C_NCONFIG#")
			(options
				(clearance outline)
				(anchor circle)
			)
			(primitives
				(gr_poly
					(pts
						(arc
							(start -0.2032 -0.2794)
							(mid -0.239121 -0.264521)
							(end -0.254 -0.2286)
						)
						(arc
							(start -0.254 0.2286)
							(mid -0.239121 0.264521)
							(end -0.2032 0.2794)
						)
						(arc
							(start 0.2032 0.2794)
							(mid 0.239121 0.264521)
							(end 0.254 0.2286)
						)
						(arc
							(start 0.254 -0.2286)
							(mid 0.239121 -0.264521)
							(end 0.2032 -0.2794)
						)
					)
					(width 0)
					(fill yes)
				)
			)
		)
	)
)
